(kicad_pcb
	(version 20260206)
	(generator "pcbnew")
	(generator_version "10.0")
	(general
		(thickness 1.6)
		(legacy_teardrops no)
	)
	(paper "A4")
	(title_block
		(title "15969-1a.1015WZS0858.brd")
		(comment 1 "Tioga Pass / footprints 1-7 of 295")
	)
	(layers
		(0 "F.Cu" signal "TOP")
		(4 "In1.Cu" signal "L2GND")
		(6 "In2.Cu" signal "L3")
		(8 "In3.Cu" signal "L4")
		(10 "In4.Cu" signal "L5GND")
		(2 "B.Cu" signal "BOTTOM")
		(9 "F.Adhes" user "F.Adhesive")
		(11 "B.Adhes" user "B.Adhesive")
		(13 "F.Paste" user "Package Geometry/Pastemask Top")
		(15 "B.Paste" user "Package Geometry/Pastemask Bottom")
		(5 "F.SilkS" user "Ref Des/Silkscreen Top")
		(7 "B.SilkS" user "Ref Des/Silkscreen Bottom")
		(1 "F.Mask" user "Board Geometry/Soldermask Top")
		(3 "B.Mask" user "Board Geometry/Soldermask Bottom")
		(17 "Dwgs.User" user "User.Drawings")
		(19 "Cmts.User" user "User.Comments")
		(21 "Eco1.User" user "User.Eco1")
		(23 "Eco2.User" user "User.Eco2")
		(25 "Edge.Cuts" user "Board Geometry/Outline")
		(27 "Margin" user)
		(31 "F.CrtYd" user "Package Geometry/Place Bound Top")
		(29 "B.CrtYd" user "Package Geometry/Place Bound Bottom")
		(35 "F.Fab" user "Ref Des/Assembly Top")
		(33 "B.Fab" user "Ref Des/Assembly Bottom")
	)
	(footprint ""
		(layer "F.Cu")
		(at 43.688 -2.9591 90)
		(property "Reference" "C27"
			(at 0 0 90)
			(layer "F.SilkS")
			(hide yes)
			(effects
				(font
					(size 1.27 1.27)
				)
			)
		)
		(property "Value" "SC10U6D3V3MX-7-GP-U"
			(at 0 -2.8194 90)
			(unlocked yes)
			(layer "F.Fab")
			(hide yes)
			(effects
				(font
					(size 1.016 1.016)
					(thickness 0.1524)
				)
			)
		)
		(property "Device Type" "C603H40"
			(at 0 -4.3434 90)
			(unlocked yes)
			(layer "F.Fab")
			(hide yes)
			(effects
				(font
					(size 1.016 1.016)
					(thickness 0.1524)
				)
			)
		)
		(duplicate_pad_numbers_are_jumpers no)
		(fp_line
			(start 0.508 0)
			(end -0.508 0)
			(stroke
				(width 0.2032)
				(type default)
			)
			(layer "F.SilkS")
		)
		(fp_rect
			(start -0.5842 1.3335)
			(end 0.5842 -1.3335)
			(stroke
				(width 0)
				(type default)
			)
			(fill no)
			(layer "F.CrtYd")
		)
		(fp_rect
			(start -0.5842 1.3335)
			(end 0.5842 -1.3335)
			(stroke
				(width 0)
				(type default)
			)
			(fill no)
			(layer "F.Fab")
		)
		(pad "1" smd custom
			(at 0 -0.762 90)
			(size 0.2159 0.2159)
			(layers "F.Cu" "F.Mask" "F.Paste")
			(net "P3V3_STBY")
			(options
				(clearance outline)
				(anchor circle)
			)
			(primitives
				(gr_poly
					(pts
						(arc
							(start -0.3302 -0.4318)
							(mid -0.402042 -0.402042)
							(end -0.4318 -0.3302)
						)
						(arc
							(start -0.4318 0.3302)
							(mid -0.402042 0.402042)
							(end -0.3302 0.4318)
						)
						(arc
							(start 0.3302 0.4318)
							(mid 0.402042 0.402042)
							(end 0.4318 0.3302)
						)
						(arc
							(start 0.4318 -0.3302)
							(mid 0.402042 -0.402042)
							(end 0.3302 -0.4318)
						)
					)
					(width 0)
					(fill yes)
				)
			)
		)
		(pad "2" smd custom
			(at 0 0.762 90)
			(size 0.2159 0.2159)
			(layers "F.Cu" "F.Mask" "F.Paste")
			(net "GND")
			(options
				(clearance outline)
				(anchor circle)
			)
			(primitives
				(gr_poly
					(pts
						(arc
							(start -0.3302 -0.4318)
							(mid -0.402042 -0.402042)
							(end -0.4318 -0.3302)
						)
						(arc
							(start -0.4318 0.3302)
							(mid -0.402042 0.402042)
							(end -0.3302 0.4318)
						)
						(arc
							(start 0.3302 0.4318)
							(mid 0.402042 0.402042)
							(end 0.4318 0.3302)
						)
						(arc
							(start 0.4318 -0.3302)
							(mid 0.402042 -0.402042)
							(end 0.3302 -0.4318)
						)
					)
					(width 0)
					(fill yes)
				)
			)
		)
	)
	(footprint ""
		(layer "F.Cu")
		(at 83.3628 -21.1328)
		(property "Reference" "R43"
			(at 0 0 0)
			(layer "F.SilkS")
			(hide yes)
			(effects
				(font
					(size 1.27 1.27)
				)
			)
		)
		(property "Value" "3K3R2F-2-GP"
			(at 0.064008 -3.993896 0)
			(unlocked yes)
			(layer "F.Fab")
			(hide yes)
			(effects
				(font
					(size 1.016 1.016)
					(thickness 0.1524)
				)
			)
		)
		(property "Device Type" "R402H16"
			(at 0.064008 -5.517896 0)
			(unlocked yes)
			(layer "F.Fab")
			(hide yes)
			(effects
				(font
					(size 1.016 1.016)
					(thickness 0.1524)
				)
			)
		)
		(duplicate_pad_numbers_are_jumpers no)
		(fp_line
			(start -0.508 -0.9398)
			(end -0.508 0.9398)
			(stroke
				(width 0.1524)
				(type default)
			)
			(layer "F.SilkS")
		)
		(fp_line
			(start 0.508 -0.9398)
			(end -0.508 -0.9398)
			(stroke
				(width 0.1524)
				(type default)
			)
			(layer "F.SilkS")
		)
		(fp_rect
			(start -0.508 0.9398)
			(end 0.508 -0.9398)
			(stroke
				(width 0)
				(type default)
			)
			(fill no)
			(layer "F.CrtYd")
		)
		(fp_rect
			(start -0.508 0.9398)
			(end 0.508 -0.9398)
			(stroke
				(width 0)
				(type default)
			)
			(fill no)
			(layer "F.Fab")
		)
		(pad "1" smd custom
			(at 0 -0.4445)
			(size 0.1397 0.1397)
			(layers "F.Cu" "F.Mask" "F.Paste")
			(net "RESET_IN")
			(options
				(clearance outline)
				(anchor circle)
			)
			(primitives
				(gr_poly
					(pts
						(arc
							(start -0.1778 -0.2794)
							(mid -0.249642 -0.249642)
							(end -0.2794 -0.1778)
						)
						(arc
							(start -0.2794 0.1778)
							(mid -0.249642 0.249642)
							(end -0.1778 0.2794)
						)
						(arc
							(start 0.1778 0.2794)
							(mid 0.249642 0.249642)
							(end 0.2794 0.1778)
						)
						(arc
							(start 0.2794 -0.1778)
							(mid 0.249642 -0.249642)
							(end 0.1778 -0.2794)
						)
					)
					(width 0)
					(fill yes)
				)
			)
		)
		(pad "2" smd custom
			(at 0 0.4445)
			(size 0.1397 0.1397)
			(layers "F.Cu" "F.Mask" "F.Paste")
			(net "GND")
			(options
				(clearance outline)
				(anchor circle)
			)
			(primitives
				(gr_poly
					(pts
						(arc
							(start -0.1778 -0.2794)
							(mid -0.249642 -0.249642)
							(end -0.2794 -0.1778)
						)
						(arc
							(start -0.2794 0.1778)
							(mid -0.249642 0.249642)
							(end -0.1778 0.2794)
						)
						(arc
							(start 0.1778 0.2794)
							(mid 0.249642 0.249642)
							(end 0.2794 0.1778)
						)
						(arc
							(start 0.2794 -0.1778)
							(mid 0.249642 -0.249642)
							(end 0.1778 -0.2794)
						)
					)
					(width 0)
					(fill yes)
				)
			)
		)
	)
	(footprint ""
		(layer "F.Cu")
		(at 118.7958 -33.4264 90)
		(property "Reference" "RU26"
			(at 0 0 90)
			(layer "F.SilkS")
			(hide yes)
			(effects
				(font
					(size 1.27 1.27)
				)
			)
		)
		(property "Value" "10KR2F-2-GP"
			(at 0.064008 -3.993896 90)
			(unlocked yes)
			(layer "F.Fab")
			(hide yes)
			(effects
				(font
					(size 1.016 1.016)
					(thickness 0.1524)
				)
			)
		)
		(property "Device Type" "R402H16"
			(at 0.064008 -5.517896 90)
			(unlocked yes)
			(layer "F.Fab")
			(hide yes)
			(effects
				(font
					(size 1.016 1.016)
					(thickness 0.1524)
				)
			)
		)
		(duplicate_pad_numbers_are_jumpers no)
		(fp_line
			(start 0.508 -0.9398)
			(end -0.508 -0.9398)
			(stroke
				(width 0.1524)
				(type default)
			)
			(layer "F.SilkS")
		)
		(fp_line
			(start -0.508 -0.9398)
			(end -0.508 0.9398)
			(stroke
				(width 0.1524)
				(type default)
			)
			(layer "F.SilkS")
		)
		(fp_rect
			(start -0.508 0.9398)
			(end 0.508 -0.9398)
			(stroke
				(width 0)
				(type default)
			)
			(fill no)
			(layer "F.CrtYd")
		)
		(fp_rect
			(start -0.508 0.9398)
			(end 0.508 -0.9398)
			(stroke
				(width 0)
				(type default)
			)
			(fill no)
			(layer "F.Fab")
		)
		(pad "1" smd custom
			(at 0 -0.4445 90)
			(size 0.1397 0.1397)
			(layers "F.Cu" "F.Mask" "F.Paste")
			(net "P3V3_USB_HUB")
			(options
				(clearance outline)
				(anchor circle)
			)
			(primitives
				(gr_poly
					(pts
						(arc
							(start -0.1778 -0.2794)
							(mid -0.249642 -0.249642)
							(end -0.2794 -0.1778)
						)
						(arc
							(start -0.2794 0.1778)
							(mid -0.249642 0.249642)
							(end -0.1778 0.2794)
						)
						(arc
							(start 0.1778 0.2794)
							(mid 0.249642 0.249642)
							(end 0.2794 0.1778)
						)
						(arc
							(start 0.2794 -0.1778)
							(mid 0.249642 -0.249642)
							(end 0.1778 -0.2794)
						)
					)
					(width 0)
					(fill yes)
				)
			)
		)
		(pad "2" smd custom
			(at 0 0.4445 90)
			(size 0.1397 0.1397)
			(layers "F.Cu" "F.Mask" "F.Paste")
			(net "USB_DN2")
			(options
				(clearance outline)
				(anchor circle)
			)
			(primitives
				(gr_poly
					(pts
						(arc
							(start -0.1778 -0.2794)
							(mid -0.249642 -0.249642)
							(end -0.2794 -0.1778)
						)
						(arc
							(start -0.2794 0.1778)
							(mid -0.249642 0.249642)
							(end -0.1778 0.2794)
						)
						(arc
							(start 0.1778 0.2794)
							(mid 0.249642 0.249642)
							(end 0.2794 0.1778)
						)
						(arc
							(start 0.2794 -0.1778)
							(mid 0.249642 -0.249642)
							(end 0.1778 -0.2794)
						)
					)
					(width 0)
					(fill yes)
				)
			)
		)
	)
	(footprint ""
		(layer "F.Cu")
		(at 42.7482 -0.1651 90)
		(property "Reference" "Q1"
			(at 0 0 90)
			(layer "F.SilkS")
			(hide yes)
			(effects
				(font
					(size 1.27 1.27)
				)
			)
		)
		(property "Value" "2N7002KDW-1-GP"
			(at -2.3622 -8.2042 90)
			(unlocked yes)
			(layer "F.Fab")
			(hide yes)
			(effects
				(font
					(size 1.016 1.016)
					(thickness 0.1524)
				)
			)
		)
		(property "Device Type" "SOT-363H44"
			(at -2.3622 -10.1092 90)
			(unlocked yes)
			(layer "F.Fab")
			(hide yes)
			(effects
				(font
					(size 1.016 1.016)
					(thickness 0.1524)
				)
			)
		)
		(duplicate_pad_numbers_are_jumpers no)
		(fp_line
			(start 1.4478 -1.7018)
			(end -1.4478 -1.7018)
			(stroke
				(width 0.1524)
				(type default)
			)
			(layer "F.SilkS")
		)
		(fp_line
			(start -1.4478 -1.7018)
			(end -1.4478 1.7018)
			(stroke
				(width 0.1524)
				(type default)
			)
			(layer "F.SilkS")
		)
		(fp_line
			(start -1.27 1.524)
			(end -1.27 0.6604)
			(stroke
				(width 0.4826)
				(type default)
			)
			(layer "F.SilkS")
		)
		(fp_line
			(start 1.4478 1.7018)
			(end 1.4478 -1.7018)
			(stroke
				(width 0.1524)
				(type default)
			)
			(layer "F.SilkS")
		)
		(fp_line
			(start -1.4478 1.7018)
			(end 1.4478 1.7018)
			(stroke
				(width 0.1524)
				(type default)
			)
			(layer "F.SilkS")
		)
		(fp_poly
			(pts
				(xy -1.524 -1.778) (xy 1.524 -1.778) (xy 1.524 1.778) (xy -1.524 1.778)
			)
			(stroke
				(width 0)
				(type default)
			)
			(fill no)
			(layer "F.CrtYd")
		)
		(fp_poly
			(pts
				(xy -1.524 -1.778) (xy 1.524 -1.778) (xy 1.524 1.778) (xy -1.524 1.778)
			)
			(stroke
				(width 0)
				(type default)
			)
			(fill no)
			(layer "F.Fab")
		)
		(pad "1" smd rect
			(at -0.65024 0.9398 90)
			(size 0.4064 1.016)
			(layers "F.Cu" "F.Mask" "F.Paste")
			(net "GND")
		)
		(pad "2" smd rect
			(at 0 0.9398 90)
			(size 0.4064 1.016)
			(layers "F.Cu" "F.Mask" "F.Paste")
			(net "SMB_PCH_ALERT_N")
		)
		(pad "3" smd rect
			(at 0.65024 0.9398 90)
			(size 0.4064 1.016)
			(layers "F.Cu" "F.Mask" "F.Paste")
			(net "SMB_PCH_ALERT_R_N")
		)
		(pad "4" smd rect
			(at 0.65024 -0.9398 90)
			(size 0.4064 1.016)
			(layers "F.Cu" "F.Mask" "F.Paste")
			(net "GND")
		)
		(pad "5" smd rect
			(at 0 -0.9398 90)
			(size 0.4064 1.016)
			(layers "F.Cu" "F.Mask" "F.Paste")
			(net "SMB_PCH_ALERT")
		)
		(pad "6" smd rect
			(at -0.65024 -0.9398 90)
			(size 0.4064 1.016)
			(layers "F.Cu" "F.Mask" "F.Paste")
			(net "SMB_PCH_ALERT")
		)
	)
	(footprint ""
		(layer "F.Cu")
		(at 32.40024 -24.08682 180)
		(property "Reference" "R113"
			(at 0 0 180)
			(layer "F.SilkS")
			(hide yes)
			(effects
				(font
					(size 1.27 1.27)
				)
			)
		)
		(property "Value" "0R2F-1-GP"
			(at 0.064008 -3.993896 180)
			(unlocked yes)
			(layer "F.Fab")
			(hide yes)
			(effects
				(font
					(size 1.016 1.016)
					(thickness 0.1524)
				)
			)
		)
		(property "Device Type" "R402H16"
			(at 0.064008 -5.517896 180)
			(unlocked yes)
			(layer "F.Fab")
			(hide yes)
			(effects
				(font
					(size 1.016 1.016)
					(thickness 0.1524)
				)
			)
		)
		(duplicate_pad_numbers_are_jumpers no)
		(fp_line
			(start 0.508 -0.9398)
			(end -0.508 -0.9398)
			(stroke
				(width 0.1524)
				(type default)
			)
			(layer "F.SilkS")
		)
		(fp_line
			(start -0.508 -0.9398)
			(end -0.508 0.9398)
			(stroke
				(width 0.1524)
				(type default)
			)
			(layer "F.SilkS")
		)
		(fp_rect
			(start -0.508 0.9398)
			(end 0.508 -0.9398)
			(stroke
				(width 0)
				(type default)
			)
			(fill no)
			(layer "F.CrtYd")
		)
		(fp_rect
			(start -0.508 0.9398)
			(end 0.508 -0.9398)
			(stroke
				(width 0)
				(type default)
			)
			(fill no)
			(layer "F.Fab")
		)
		(pad "1" smd custom
			(at 0 -0.4445 180)
			(size 0.1397 0.1397)
			(layers "F.Cu" "F.Mask" "F.Paste")
			(net "SMCLK_PCH_SLOT3")
			(options
				(clearance outline)
				(anchor circle)
			)
			(primitives
				(gr_poly
					(pts
						(arc
							(start -0.1778 -0.2794)
							(mid -0.249642 -0.249642)
							(end -0.2794 -0.1778)
						)
						(arc
							(start -0.2794 0.1778)
							(mid -0.249642 0.249642)
							(end -0.1778 0.2794)
						)
						(arc
							(start 0.1778 0.2794)
							(mid 0.249642 0.249642)
							(end 0.2794 0.1778)
						)
						(arc
							(start 0.2794 -0.1778)
							(mid 0.249642 -0.249642)
							(end 0.1778 -0.2794)
						)
					)
					(width 0)
					(fill yes)
				)
			)
		)
		(pad "2" smd custom
			(at 0 0.4445 180)
			(size 0.1397 0.1397)
			(layers "F.Cu" "F.Mask" "F.Paste")
			(net "SMCLK_PCH_SLOT3_R")
			(options
				(clearance outline)
				(anchor circle)
			)
			(primitives
				(gr_poly
					(pts
						(arc
							(start -0.1778 -0.2794)
							(mid -0.249642 -0.249642)
							(end -0.2794 -0.1778)
						)
						(arc
							(start -0.2794 0.1778)
							(mid -0.249642 0.249642)
							(end -0.1778 0.2794)
						)
						(arc
							(start 0.1778 0.2794)
							(mid 0.249642 0.249642)
							(end 0.2794 0.1778)
						)
						(arc
							(start 0.2794 -0.1778)
							(mid 0.249642 -0.249642)
							(end 0.1778 -0.2794)
						)
					)
					(width 0)
					(fill yes)
				)
			)
		)
	)
	(footprint ""
		(layer "F.Cu")
		(at 107.7468 3.1496)
		(property "Reference" "R14"
			(at 0 0 0)
			(layer "F.SilkS")
			(hide yes)
			(effects
				(font
					(size 1.27 1.27)
				)
			)
		)
		(property "Value" "10KR2F-2-GP"
			(at 0.064008 -3.993896 0)
			(unlocked yes)
			(layer "F.Fab")
			(hide yes)
			(effects
				(font
					(size 1.016 1.016)
					(thickness 0.1524)
				)
			)
		)
		(property "Device Type" "R402H16"
			(at 0.064008 -5.517896 0)
			(unlocked yes)
			(layer "F.Fab")
			(hide yes)
			(effects
				(font
					(size 1.016 1.016)
					(thickness 0.1524)
				)
			)
		)
		(duplicate_pad_numbers_are_jumpers no)
		(fp_line
			(start -0.508 -0.9398)
			(end -0.508 0.9398)
			(stroke
				(width 0.1524)
				(type default)
			)
			(layer "F.SilkS")
		)
		(fp_line
			(start 0.508 -0.9398)
			(end -0.508 -0.9398)
			(stroke
				(width 0.1524)
				(type default)
			)
			(layer "F.SilkS")
		)
		(fp_rect
			(start -0.508 0.9398)
			(end 0.508 -0.9398)
			(stroke
				(width 0)
				(type default)
			)
			(fill no)
			(layer "F.CrtYd")
		)
		(fp_rect
			(start -0.508 0.9398)
			(end 0.508 -0.9398)
			(stroke
				(width 0)
				(type default)
			)
			(fill no)
			(layer "F.Fab")
		)
		(pad "1" smd custom
			(at 0 -0.4445)
			(size 0.1397 0.1397)
			(layers "F.Cu" "F.Mask" "F.Paste")
			(net "SMB_B_HUB_A1")
			(options
				(clearance outline)
				(anchor circle)
			)
			(primitives
				(gr_poly
					(pts
						(arc
							(start -0.1778 -0.2794)
							(mid -0.249642 -0.249642)
							(end -0.2794 -0.1778)
						)
						(arc
							(start -0.2794 0.1778)
							(mid -0.249642 0.249642)
							(end -0.1778 0.2794)
						)
						(arc
							(start 0.1778 0.2794)
							(mid 0.249642 0.249642)
							(end 0.2794 0.1778)
						)
						(arc
							(start 0.2794 -0.1778)
							(mid 0.249642 -0.249642)
							(end 0.1778 -0.2794)
						)
					)
					(width 0)
					(fill yes)
				)
			)
		)
		(pad "2" smd custom
			(at 0 0.4445)
			(size 0.1397 0.1397)
			(layers "F.Cu" "F.Mask" "F.Paste")
			(net "GND")
			(options
				(clearance outline)
				(anchor circle)
			)
			(primitives
				(gr_poly
					(pts
						(arc
							(start -0.1778 -0.2794)
							(mid -0.249642 -0.249642)
							(end -0.2794 -0.1778)
						)
						(arc
							(start -0.2794 0.1778)
							(mid -0.249642 0.249642)
							(end -0.1778 0.2794)
						)
						(arc
							(start 0.1778 0.2794)
							(mid 0.249642 0.249642)
							(end 0.2794 0.1778)
						)
						(arc
							(start 0.2794 -0.1778)
							(mid 0.249642 -0.249642)
							(end 0.1778 -0.2794)
						)
					)
					(width 0)
					(fill yes)
				)
			)
		)
	)
	(footprint ""
		(layer "F.Cu")
		(at 126.619 -21.1582 180)
		(property "Reference" "C41"
			(at 0 0 180)
			(layer "F.SilkS")
			(hide yes)
			(effects
				(font
					(size 1.27 1.27)
				)
			)
		)
		(property "Value" "SCD1U16V2KX-3GP"
			(at 1.1811 -2.7051 180)
			(unlocked yes)
			(layer "F.Fab")
			(hide yes)
			(effects
				(font
					(size 1.016 1.016)
					(thickness 0.1524)
				)
			)
		)
		(property "Device Type" "C402H22"
			(at 1.1811 -4.2291 180)
			(unlocked yes)
			(layer "F.Fab")
			(hide yes)
			(effects
				(font
					(size 1.016 1.016)
					(thickness 0.1524)
				)
			)
		)
		(duplicate_pad_numbers_are_jumpers no)
		(fp_rect
			(start -0.4318 0.9525)
			(end 0.4318 -0.9525)
			(stroke
				(width 0)
				(type default)
			)
			(fill no)
			(layer "F.CrtYd")
		)
		(fp_rect
			(start -0.4318 0.9525)
			(end 0.4318 -0.9525)
			(stroke
				(width 0)
				(type default)
			)
			(fill no)
			(layer "F.Fab")
		)
		(pad "1" smd custom
			(at 0 -0.4445 180)
			(size 0.1524 0.1524)
			(layers "F.Cu" "F.Mask" "F.Paste")
			(net "P3V3_STBY")
			(options
				(clearance outline)
				(anchor circle)
			)
			(primitives
				(gr_poly
					(pts
						(arc
							(start 0.3048 -0.2032)
							(mid 0.275042 -0.275042)
							(end 0.2032 -0.3048)
						)
						(arc
							(start -0.2032 -0.3048)
							(mid -0.275042 -0.275042)
							(end -0.3048 -0.2032)
						)
						(arc
							(start -0.3048 0.2032)
							(mid -0.275042 0.275042)
							(end -0.2032 0.3048)
						)
						(arc
							(start 0.2032 0.3048)
							(mid 0.275042 0.275042)
							(end 0.3048 0.2032)
						)
					)
					(width 0)
					(fill yes)
				)
			)
		)
		(pad "2" smd custom
			(at 0 0.4445 180)
			(size 0.1524 0.1524)
			(layers "F.Cu" "F.Mask" "F.Paste")
			(net "GND")
			(options
				(clearance outline)
				(anchor circle)
			)
			(primitives
				(gr_poly
					(pts
						(arc
							(start 0.3048 -0.2032)
							(mid 0.275042 -0.275042)
							(end 0.2032 -0.3048)
						)
						(arc
							(start -0.2032 -0.3048)
							(mid -0.275042 -0.275042)
							(end -0.3048 -0.2032)
						)
						(arc
							(start -0.3048 0.2032)
							(mid -0.275042 0.275042)
							(end -0.2032 0.3048)
						)
						(arc
							(start 0.2032 0.3048)
							(mid 0.275042 0.275042)
							(end 0.3048 0.2032)
						)
					)
					(width 0)
					(fill yes)
				)
			)
		)
	)
)
